(kicad_pcb
	(version 20211014)
	(generator pcbnew)
	(general
    (thickness 1.6)
  )
	(paper "A4")
	(title_block
    (title "SA800U (Snapdragon 845) Baseboard")
    (date "2023-10-19")
    (rev "1.0.3")
    (company "Antmicro Ltd.")
    (comment 1 "www.antmicro.com")
		(comment 9 "footprints 38-47 of 589")
	)
	(layers
    (0 "F.Cu" signal)
    (1 "In1.Cu" power)
    (2 "In2.Cu" signal)
    (3 "In3.Cu" signal)
    (4 "In4.Cu" power)
    (31 "B.Cu" signal)
    (32 "B.Adhes" user "B.Adhesive")
    (33 "F.Adhes" user "F.Adhesive")
    (34 "B.Paste" user)
    (35 "F.Paste" user)
    (36 "B.SilkS" user "B.Silkscreen")
    (37 "F.SilkS" user "F.Silkscreen")
    (38 "B.Mask" user)
    (39 "F.Mask" user)
    (40 "Dwgs.User" user "User.Drawings")
    (41 "Cmts.User" user "User.Comments")
    (42 "Eco1.User" user "User.Eco1")
    (43 "Eco2.User" user "User.Eco2")
    (44 "Edge.Cuts" user)
    (45 "Margin" user)
    (46 "B.CrtYd" user "B.Courtyard")
    (47 "F.CrtYd" user "F.Courtyard")
    (48 "B.Fab" user)
    (49 "F.Fab" user)
  )
	(footprint "sa800u-baseboard-hw-footprints:LED_0603_1608Metric_G" (layer "F.Cu")
    (tedit 60C2DD7B)
    (at 93.4 150.16 -90)
    (descr "LED SMD 0603 Green")
    (tags "LED SMD 0603 Green")
    (property "Author" "Antmicro")
    (property "License" "Apache-2.0")
    (property "MPN" "KP-1608ZGC")
    (property "Manufacturer" "Kingbright")
    (property "Sheetfile" "psu.kicad_sch")
    (property "Sheetname" "PSU")
    (attr smd)
    (fp_text reference "D25" (at 1.17 -2.07 -90) (layer "F.SilkS")
      (effects (font (size 0.7 0.7) (thickness 0.15)) (justify left bottom))
    )
    (fp_text value "KP-1608EC" (at 0 1.6 -90) (layer "F.Fab")
      (effects (font (size 0.7 0.7) (thickness 0.15)) (justify left bottom))
    )
    (fp_text user "Author: Antmicro" (at -1.31 4.769 -90) (layer "F.Fab") hide
      (effects (font (size 0.7 0.7) (thickness 0.15)) (justify left bottom))
    )
    (fp_text user "${REFERENCE}" (at -1.31 3.769 -90) (layer "F.Fab") hide
      (effects (font (size 0.7 0.7) (thickness 0.15)) (justify left bottom))
    )
    (fp_text user "License: Apache-2.0" (at -1.31 5.769 -90) (layer "F.Fab") hide
      (effects (font (size 0.7 0.7) (thickness 0.15)) (justify left bottom))
    )
    (fp_line (start 1.25 0.32) (end 1.25 -0.32) (layer "F.SilkS") (width 0.15))
    (fp_line (start -0.106328 -0.200008) (end 0.093672 -0.000008) (layer "F.SilkS") (width 0.1))
    (fp_line (start -0.27 -0.35) (end 0.27 -0.35) (layer "F.SilkS") (width 0.15))
    (fp_line (start -0.27 0.351) (end 0.27 0.351) (layer "F.SilkS") (width 0.15))
    (fp_line (start 0.093672 -0.200008) (end 0.093672 0.199992) (layer "F.SilkS") (width 0.1))
    (fp_line (start 0.093672 -0.000008) (end -0.106328 0.199992) (layer "F.SilkS") (width 0.1))
    (fp_line (start -0.106328 -0.200008) (end -0.106328 0.199992) (layer "F.SilkS") (width 0.1))
    (fp_line (start 0.093672 -0.000008) (end 0.293672 -0.000008) (layer "F.SilkS") (width 0.1))
    (fp_line (start -0.106328 -0.000008) (end -0.29 0) (layer "F.SilkS") (width 0.1))
    (fp_rect (start 1.26 0.65) (end -1.26 -0.65) (layer "F.CrtYd") (width 0.05) (fill none))
    (fp_line (start 0.199 0.202) (end 0.199 -0.1) (layer "F.Fab") (width 0.15))
    (fp_line (start 0.199 0) (end 0.597 0) (layer "F.Fab") (width 0.15))
    (fp_line (start 0.199 -0.2) (end 0.199 -0.1) (layer "F.Fab") (width 0.15))
    (fp_line (start -0.599 0) (end -0.201 0) (layer "F.Fab") (width 0.15))
    (fp_line (start -0.201 0.202) (end 0.101 0) (layer "F.Fab") (width 0.15))
    (fp_line (start 0.101 0) (end -0.201 -0.2) (layer "F.Fab") (width 0.15))
    (fp_line (start -0.201 0) (end -0.201 0.202) (layer "F.Fab") (width 0.15))
    (fp_line (start -0.201 -0.2) (end -0.201 0) (layer "F.Fab") (width 0.15))
    (fp_rect (start -0.848 -0.4) (end 0.85 0.402) (layer "F.Fab") (width 0.15) (fill none))
    (pad "1" smd rect (at -0.75 0 90) (size 0.8 0.8) (layers "F.Cu" "F.Paste" "F.Mask")
      (net 142 "PD_VDD") (pinfunction "1") (pintype "passive"))
    (pad "2" smd rect (at 0.75 0 90) (size 0.8 0.8) (layers "F.Cu" "F.Paste" "F.Mask")
      (net 376 "Net-(D25-Pad2)") (pinfunction "2") (pintype "passive"))
  )
	(footprint "sa800u-baseboard-hw-footprints:FB_0603_1608Metric" (layer "F.Cu")
    (tedit 618B9E9E)
    (at 137.1 145 -90)
    (property "Author" "Antmicro")
    (property "License" "Apache-2.0")
    (property "MPN" "BLM18SG121TN1D")
    (property "Manufacturer" "Murata")
    (property "Sheetfile" "hdmi-converter.kicad_sch")
    (property "Sheetname" "HDMI converter")
    (attr smd)
    (fp_text reference "FB2" (at 0.93 0.72 -90) (layer "F.SilkS")
      (effects (font (size 0.7 0.7) (thickness 0.15)) (justify left bottom))
    )
    (fp_text value "FB_120Z_3A_0603" (at 0 1.5 -90) (layer "F.Fab")
      (effects (font (size 0.7 0.7) (thickness 0.15)) (justify left bottom))
    )
    (fp_text user "License: Apache-2.0" (at -1.653 5.9 -90) (layer "F.Fab") hide
      (effects (font (size 0.7 0.7) (thickness 0.15)) (justify left bottom))
    )
    (fp_text user "Author: Antmicro" (at -1.653 3.162 -90) (layer "F.Fab") hide
      (effects (font (size 0.7 0.7) (thickness 0.15)) (justify left bottom))
    )
    (fp_text user "${REFERENCE}" (at -1.653 4.6 -90) (layer "F.Fab") hide
      (effects (font (size 0.7 0.7) (thickness 0.15)) (justify left bottom))
    )
    (fp_line (start -0.196 0.406) (end 0.193 0.406) (layer "F.SilkS") (width 0.15))
    (fp_line (start -0.196 -0.408) (end 0.193 -0.408) (layer "F.SilkS") (width 0.15))
    (fp_rect (start -1.3 -0.6) (end 1.3 0.6) (layer "F.CrtYd") (width 0.05) (fill none))
    (fp_line (start 0.8 -0.408) (end -0.803 -0.408) (layer "F.Fab") (width 0.15))
    (fp_line (start 0.8 0.406) (end -0.803 0.406) (layer "F.Fab") (width 0.15))
    (fp_line (start 0.8 -0.408) (end 0.8 0.406) (layer "F.Fab") (width 0.15))
    (fp_line (start -0.803 0.406) (end -0.803 -0.408) (layer "F.Fab") (width 0.15))
    (pad "1" smd roundrect (at -0.891 0 270) (size 0.762 1.09) (layers "F.Cu" "F.Paste" "F.Mask") (roundrect_rratio 0.15)
      (net 133 "5V_SYS") (pintype "passive"))
    (pad "2" smd roundrect (at 0.888 0 270) (size 0.762 1.09) (layers "F.Cu" "F.Paste" "F.Mask") (roundrect_rratio 0.15)
      (net 244 "/HDMI converter/5V_HDMI_FB_D") (pintype "passive"))
  )
	(footprint "sa800u-baseboard-hw-footprints:R_0402_1005Metric" (layer "F.Cu")
    (tedit 5FD9C158)
    (at 119 109.8 180)
    (descr "Resistor SMD 0402")
    (tags "resistor SMD 0402")
    (property "Author" "Antmicro")
    (property "License" "Apache-2.0")
    (property "MPN" "CR0402-FX-2001GLF")
    (property "Manufacturer" "Bourns")
    (property "Sheetfile" "lcm.kicad_sch")
    (property "Sheetname" "LCM")
    (property "Tolerance" "1%")
    (property "Val" "2k")
    (attr smd)
    (fp_text reference "R65" (at 1.04 -1.24 180) (layer "F.SilkS")
      (effects (font (size 0.7 0.7) (thickness 0.15)) (justify left bottom))
    )
    (fp_text value "R_2k_0402" (at 0 1.4 180) (layer "F.Fab")
      (effects (font (size 0.7 0.7) (thickness 0.15)) (justify left bottom))
    )
    (fp_text user "${REFERENCE}" (at -0.95 3.168 180) (layer "F.Fab") hide
      (effects (font (size 0.7 0.7) (thickness 0.15)) (justify left bottom))
    )
    (fp_text user "Author: Antmicro" (at -0.95 4.169 180) (layer "F.Fab") hide
      (effects (font (size 0.7 0.7) (thickness 0.15)) (justify left bottom))
    )
    (fp_text user "License: Apache-2.0" (at -0.95 5.169 180) (layer "F.Fab") hide
      (effects (font (size 0.7 0.7) (thickness 0.15)) (justify left bottom))
    )
    (fp_rect (start -0.93 -0.47) (end 0.93 0.47) (layer "F.CrtYd") (width 0.05) (fill none))
    (fp_rect (start -0.5 -0.25) (end 0.5 0.25) (layer "F.Fab") (width 0.15) (fill none))
    (pad "1" smd roundrect (at -0.485 0 180) (size 0.59 0.64) (layers "F.Cu" "F.Paste" "F.Mask") (roundrect_rratio 0.25)
      (net 82 "TP_I2C_SDA") (pintype "passive"))
    (pad "2" smd roundrect (at 0.485 0 180) (size 0.59 0.64) (layers "F.Cu" "F.Paste" "F.Mask") (roundrect_rratio 0.25)
      (net 139 "LVS1A_1V8") (pintype "passive"))
  )
	(footprint "sa800u-baseboard-hw-footprints:R_0402_1005Metric" (layer "F.Cu")
    (tedit 5FD9C158)
    (at 122.8 109.8)
    (descr "Resistor SMD 0402")
    (tags "resistor SMD 0402")
    (property "Author" "Antmicro")
    (property "License" "Apache-2.0")
    (property "MPN" "CR0402-FX-2001GLF")
    (property "Manufacturer" "Bourns")
    (property "Sheetfile" "lcm.kicad_sch")
    (property "Sheetname" "LCM")
    (property "Tolerance" "1%")
    (property "Val" "2k")
    (attr smd)
    (fp_text reference "R66" (at 0.79 0.39) (layer "F.SilkS")
      (effects (font (size 0.7 0.7) (thickness 0.15)) (justify left bottom))
    )
    (fp_text value "R_2k_0402" (at 0 1.4) (layer "F.Fab")
      (effects (font (size 0.7 0.7) (thickness 0.15)) (justify left bottom))
    )
    (fp_text user "${REFERENCE}" (at -0.95 3.168) (layer "F.Fab") hide
      (effects (font (size 0.7 0.7) (thickness 0.15)) (justify left bottom))
    )
    (fp_text user "License: Apache-2.0" (at -0.95 5.169) (layer "F.Fab") hide
      (effects (font (size 0.7 0.7) (thickness 0.15)) (justify left bottom))
    )
    (fp_text user "Author: Antmicro" (at -0.95 4.169) (layer "F.Fab") hide
      (effects (font (size 0.7 0.7) (thickness 0.15)) (justify left bottom))
    )
    (fp_rect (start -0.93 -0.47) (end 0.93 0.47) (layer "F.CrtYd") (width 0.05) (fill none))
    (fp_rect (start -0.5 -0.25) (end 0.5 0.25) (layer "F.Fab") (width 0.15) (fill none))
    (pad "1" smd roundrect (at -0.485 0) (size 0.59 0.64) (layers "F.Cu" "F.Paste" "F.Mask") (roundrect_rratio 0.25)
      (net 81 "TP_I2C_SCL") (pintype "passive"))
    (pad "2" smd roundrect (at 0.485 0) (size 0.59 0.64) (layers "F.Cu" "F.Paste" "F.Mask") (roundrect_rratio 0.25)
      (net 139 "LVS1A_1V8") (pintype "passive"))
  )
	(footprint "sa800u-baseboard-hw-footprints:R_0402_1005Metric" (layer "F.Cu")
    (tedit 5FD9C158)
    (at 122.8 107.8)
    (descr "Resistor SMD 0402")
    (tags "resistor SMD 0402")
    (property "Author" "Antmicro")
    (property "License" "Apache-2.0")
    (property "MPN" "CR0402-FX-2001GLF")
    (property "Manufacturer" "Bourns")
    (property "Sheetfile" "lcm.kicad_sch")
    (property "Sheetname" "LCM")
    (property "Tolerance" "1%")
    (property "Val" "2k")
    (attr smd)
    (fp_text reference "R67" (at 0.79 0.39) (layer "F.SilkS")
      (effects (font (size 0.7 0.7) (thickness 0.15)) (justify left bottom))
    )
    (fp_text value "R_2k_0402" (at 0 1.4) (layer "F.Fab")
      (effects (font (size 0.7 0.7) (thickness 0.15)) (justify left bottom))
    )
    (fp_text user "${REFERENCE}" (at -0.95 3.168) (layer "F.Fab") hide
      (effects (font (size 0.7 0.7) (thickness 0.15)) (justify left bottom))
    )
    (fp_text user "Author: Antmicro" (at -0.95 4.169) (layer "F.Fab") hide
      (effects (font (size 0.7 0.7) (thickness 0.15)) (justify left bottom))
    )
    (fp_text user "License: Apache-2.0" (at -0.95 5.169) (layer "F.Fab") hide
      (effects (font (size 0.7 0.7) (thickness 0.15)) (justify left bottom))
    )
    (fp_rect (start -0.93 -0.47) (end 0.93 0.47) (layer "F.CrtYd") (width 0.05) (fill none))
    (fp_rect (start -0.5 -0.25) (end 0.5 0.25) (layer "F.Fab") (width 0.15) (fill none))
    (pad "1" smd roundrect (at -0.485 0) (size 0.59 0.64) (layers "F.Cu" "F.Paste" "F.Mask") (roundrect_rratio 0.25)
      (net 148 "/LCM/TP_I2C_SCL_3V3") (pintype "passive"))
    (pad "2" smd roundrect (at 0.485 0) (size 0.59 0.64) (layers "F.Cu" "F.Paste" "F.Mask") (roundrect_rratio 0.25)
      (net 131 "3V3_SYS") (pintype "passive"))
  )
	(footprint "sa800u-baseboard-hw-footprints:R_0402_1005Metric" (layer "F.Cu")
    (tedit 5FD9C158)
    (at 83.4 132)
    (descr "Resistor SMD 0402")
    (tags "resistor SMD 0402")
    (property "Author" "Antmicro")
    (property "DNP" "DNP")
    (property "License" "Apache-2.0")
    (property "MPN" "CR0402-FX-1003GLF")
    (property "Manufacturer" "Bourns")
    (property "Sheetfile" "usb-pd.kicad_sch")
    (property "Sheetname" "USB-PD")
    (property "Tolerance" "1%")
    (property "Val" "100k")
    (attr exclude_from_pos_files)
    (fp_text reference "R154" (at -1.71 -2.53) (layer "F.SilkS")
      (effects (font (size 0.7 0.7) (thickness 0.15)) (justify left bottom))
    )
    (fp_text value "R_100k_0402" (at 0 1.4) (layer "F.Fab")
      (effects (font (size 0.7 0.7) (thickness 0.15)) (justify left bottom))
    )
    (fp_text user "License: Apache-2.0" (at -0.95 5.169) (layer "F.Fab") hide
      (effects (font (size 0.7 0.7) (thickness 0.15)) (justify left bottom))
    )
    (fp_text user "${REFERENCE}" (at -0.95 3.168) (layer "F.Fab") hide
      (effects (font (size 0.7 0.7) (thickness 0.15)) (justify left bottom))
    )
    (fp_text user "Author: Antmicro" (at -0.95 4.169) (layer "F.Fab") hide
      (effects (font (size 0.7 0.7) (thickness 0.15)) (justify left bottom))
    )
    (fp_rect (start -0.93 -0.47) (end 0.93 0.47) (layer "F.CrtYd") (width 0.05) (fill none))
    (fp_rect (start -0.5 -0.25) (end 0.5 0.25) (layer "F.Fab") (width 0.15) (fill none))
    (pad "1" smd roundrect (at -0.485 0) (size 0.59 0.64) (layers "F.Cu" "F.Paste" "F.Mask") (roundrect_rratio 0.25)
      (net 141 "/USB-PD/VREG_2V7") (pintype "passive"))
    (pad "2" smd roundrect (at 0.485 0) (size 0.59 0.64) (layers "F.Cu" "F.Paste" "F.Mask") (roundrect_rratio 0.25)
      (net 160 "Net-(R154-Pad2)") (pintype "passive"))
  )
	(footprint "sa800u-baseboard-hw-footprints:R_0402_1005Metric" (layer "F.Cu")
    (tedit 5FD9C158)
    (at 83.4 133)
    (descr "Resistor SMD 0402")
    (tags "resistor SMD 0402")
    (property "Author" "Antmicro")
    (property "DNP" "DNP")
    (property "License" "Apache-2.0")
    (property "MPN" "CR0402-FX-1003GLF")
    (property "Manufacturer" "Bourns")
    (property "Sheetfile" "usb-pd.kicad_sch")
    (property "Sheetname" "USB-PD")
    (property "Tolerance" "1%")
    (property "Val" "100k")
    (attr exclude_from_pos_files)
    (fp_text reference "R155" (at -1.71 -2.53) (layer "F.SilkS")
      (effects (font (size 0.7 0.7) (thickness 0.15)) (justify left bottom))
    )
    (fp_text value "R_100k_0402" (at 0 1.4) (layer "F.Fab")
      (effects (font (size 0.7 0.7) (thickness 0.15)) (justify left bottom))
    )
    (fp_text user "License: Apache-2.0" (at -0.95 5.169) (layer "F.Fab") hide
      (effects (font (size 0.7 0.7) (thickness 0.15)) (justify left bottom))
    )
    (fp_text user "${REFERENCE}" (at -0.95 3.168) (layer "F.Fab") hide
      (effects (font (size 0.7 0.7) (thickness 0.15)) (justify left bottom))
    )
    (fp_text user "Author: Antmicro" (at -0.95 4.169) (layer "F.Fab") hide
      (effects (font (size 0.7 0.7) (thickness 0.15)) (justify left bottom))
    )
    (fp_rect (start -0.93 -0.47) (end 0.93 0.47) (layer "F.CrtYd") (width 0.05) (fill none))
    (fp_rect (start -0.5 -0.25) (end 0.5 0.25) (layer "F.Fab") (width 0.15) (fill none))
    (pad "1" smd roundrect (at -0.485 0) (size 0.59 0.64) (layers "F.Cu" "F.Paste" "F.Mask") (roundrect_rratio 0.25)
      (net 141 "/USB-PD/VREG_2V7") (pintype "passive"))
    (pad "2" smd roundrect (at 0.485 0) (size 0.59 0.64) (layers "F.Cu" "F.Paste" "F.Mask") (roundrect_rratio 0.25)
      (net 411 "Net-(R155-Pad2)") (pintype "passive"))
  )
	(footprint "sa800u-baseboard-hw-footprints:R_0402_1005Metric" (layer "F.Cu")
    (tedit 5FD9C158)
    (at 84.9 132.4 90)
    (descr "Resistor SMD 0402")
    (tags "resistor SMD 0402")
    (property "Author" "Antmicro")
    (property "License" "Apache-2.0")
    (property "MPN" "CR0402-FX-1003GLF")
    (property "Manufacturer" "Bourns")
    (property "Sheetfile" "usb-pd.kicad_sch")
    (property "Sheetname" "USB-PD")
    (property "Tolerance" "1%")
    (property "Val" "100k")
    (attr smd)
    (fp_text reference "R156" (at 0.84 0.41 90) (layer "F.SilkS")
      (effects (font (size 0.7 0.7) (thickness 0.15)) (justify left bottom))
    )
    (fp_text value "R_100k_0402" (at 0 1.4 90) (layer "F.Fab")
      (effects (font (size 0.7 0.7) (thickness 0.15)) (justify left bottom))
    )
    (fp_text user "Author: Antmicro" (at -0.95 4.169 90) (layer "F.Fab") hide
      (effects (font (size 0.7 0.7) (thickness 0.15)) (justify left bottom))
    )
    (fp_text user "${REFERENCE}" (at -0.95 3.168 90) (layer "F.Fab") hide
      (effects (font (size 0.7 0.7) (thickness 0.15)) (justify left bottom))
    )
    (fp_text user "License: Apache-2.0" (at -0.95 5.169 90) (layer "F.Fab") hide
      (effects (font (size 0.7 0.7) (thickness 0.15)) (justify left bottom))
    )
    (fp_rect (start -0.93 -0.47) (end 0.93 0.47) (layer "F.CrtYd") (width 0.05) (fill none))
    (fp_rect (start -0.5 -0.25) (end 0.5 0.25) (layer "F.Fab") (width 0.15) (fill none))
    (pad "1" smd roundrect (at -0.485 0 90) (size 0.59 0.64) (layers "F.Cu" "F.Paste" "F.Mask") (roundrect_rratio 0.25)
      (net 160 "Net-(R154-Pad2)") (pintype "passive"))
    (pad "2" smd roundrect (at 0.485 0 90) (size 0.59 0.64) (layers "F.Cu" "F.Paste" "F.Mask") (roundrect_rratio 0.25)
      (net 1 "GND") (pintype "passive"))
  )
	(footprint "sa800u-baseboard-hw-footprints:R_0402_1005Metric" (layer "F.Cu")
    (tedit 5FD9C158)
    (at 83.4 134 180)
    (descr "Resistor SMD 0402")
    (tags "resistor SMD 0402")
    (property "Author" "Antmicro")
    (property "License" "Apache-2.0")
    (property "MPN" "CR0402-FX-1003GLF")
    (property "Manufacturer" "Bourns")
    (property "Sheetfile" "usb-pd.kicad_sch")
    (property "Sheetname" "USB-PD")
    (property "Tolerance" "1%")
    (property "Val" "100k")
    (attr smd)
    (fp_text reference "R157" (at 1.72 2.58 180) (layer "F.SilkS")
      (effects (font (size 0.7 0.7) (thickness 0.15)) (justify left bottom))
    )
    (fp_text value "R_100k_0402" (at 0 1.4 180) (layer "F.Fab")
      (effects (font (size 0.7 0.7) (thickness 0.15)) (justify left bottom))
    )
    (fp_text user "${REFERENCE}" (at -0.95 3.168 180) (layer "F.Fab") hide
      (effects (font (size 0.7 0.7) (thickness 0.15)) (justify left bottom))
    )
    (fp_text user "Author: Antmicro" (at -0.95 4.169 180) (layer "F.Fab") hide
      (effects (font (size 0.7 0.7) (thickness 0.15)) (justify left bottom))
    )
    (fp_text user "License: Apache-2.0" (at -0.95 5.169 180) (layer "F.Fab") hide
      (effects (font (size 0.7 0.7) (thickness 0.15)) (justify left bottom))
    )
    (fp_rect (start -0.93 -0.47) (end 0.93 0.47) (layer "F.CrtYd") (width 0.05) (fill none))
    (fp_rect (start -0.5 -0.25) (end 0.5 0.25) (layer "F.Fab") (width 0.15) (fill none))
    (pad "1" smd roundrect (at -0.485 0 180) (size 0.59 0.64) (layers "F.Cu" "F.Paste" "F.Mask") (roundrect_rratio 0.25)
      (net 411 "Net-(R155-Pad2)") (pintype "passive"))
    (pad "2" smd roundrect (at 0.485 0 180) (size 0.59 0.64) (layers "F.Cu" "F.Paste" "F.Mask") (roundrect_rratio 0.25)
      (net 1 "GND") (pintype "passive"))
  )
	(footprint "sa800u-baseboard-hw-footprints:R_0402_1005Metric" (layer "F.Cu")
    (tedit 5FD9C158)
    (at 71.55 111.85)
    (descr "Resistor SMD 0402")
    (tags "resistor SMD 0402")
    (property "Author" "Antmicro")
    (property "License" "Apache-2.0")
    (property "MPN" "CR0402-FX-1002GLF")
    (property "Manufacturer" "Bourns")
    (property "Sheetfile" "psu.kicad_sch")
    (property "Sheetname" "PSU")
    (property "Tolerance" "1%")
    (property "Val" "10k")
    (attr smd)
    (fp_text reference "R127" (at -1.59 1.3) (layer "F.SilkS")
      (effects (font (size 0.7 0.7) (thickness 0.15)) (justify left bottom))
    )
    (fp_text value "R_10k_0402" (at 0 1.4) (layer "F.Fab")
      (effects (font (size 0.7 0.7) (thickness 0.15)) (justify left bottom))
    )
    (fp_text user "Author: Antmicro" (at -0.95 4.169) (layer "F.Fab") hide
      (effects (font (size 0.7 0.7) (thickness 0.15)) (justify left bottom))
    )
    (fp_text user "License: Apache-2.0" (at -0.95 5.169) (layer "F.Fab") hide
      (effects (font (size 0.7 0.7) (thickness 0.15)) (justify left bottom))
    )
    (fp_text user "${REFERENCE}" (at -0.95 3.168) (layer "F.Fab") hide
      (effects (font (size 0.7 0.7) (thickness 0.15)) (justify left bottom))
    )
    (fp_rect (start -0.93 -0.47) (end 0.93 0.47) (layer "F.CrtYd") (width 0.05) (fill none))
    (fp_rect (start -0.5 -0.25) (end 0.5 0.25) (layer "F.Fab") (width 0.15) (fill none))
    (pad "1" smd roundrect (at -0.485 0) (size 0.59 0.64) (layers "F.Cu" "F.Paste" "F.Mask") (roundrect_rratio 0.25)
      (net 319 "3V3_SYS_EN") (pintype "passive"))
    (pad "2" smd roundrect (at 0.485 0) (size 0.59 0.64) (layers "F.Cu" "F.Paste" "F.Mask") (roundrect_rratio 0.25)
      (net 407 "Net-(R127-Pad2)") (pintype "passive"))
  )
)
